(kicad_pcb
	(version 20260206)
	(generator "pcbnew")
	(generator_version "10.0")
	(general
		(thickness 1.6)
		(legacy_teardrops no)
	)
	(paper "A4")
	(title_block
		(title "04192023_DAF0TMB3IC0_F0TG_MB_C_brd_V02_OCP.brd")
		(comment 1 "Grand Teton / footprints 8190-8195 of 8354")
	)
	(layers
		(0 "F.Cu" signal "TOP")
		(4 "In1.Cu" signal "GND")
		(6 "In2.Cu" signal "IN1")
		(8 "In3.Cu" signal "GND1")
		(10 "In4.Cu" signal "IN2")
		(12 "In5.Cu" signal "GND2")
		(14 "In6.Cu" signal "IN3")
		(16 "In7.Cu" signal "GND3")
		(18 "In8.Cu" signal "VCC")
		(20 "In9.Cu" signal "VCC1")
		(22 "In10.Cu" signal "GND4")
		(24 "In11.Cu" signal "IN4")
		(26 "In12.Cu" signal "GND5")
		(28 "In13.Cu" signal "IN5")
		(30 "In14.Cu" signal "GND6")
		(32 "In15.Cu" signal "IN6")
		(34 "In16.Cu" signal "GND7")
		(2 "B.Cu" signal "BOTTOM")
		(9 "F.Adhes" user "F.Adhesive")
		(11 "B.Adhes" user "B.Adhesive")
		(13 "F.Paste" user "Package Geometry/Pastemask Top")
		(15 "B.Paste" user "Package Geometry/Pastemask Bottom")
		(5 "F.SilkS" user "Ref Des/Silkscreen Top")
		(7 "B.SilkS" user "Ref Des/Silkscreen Bottom")
		(1 "F.Mask" user "Board Geometry/Soldermask Top")
		(3 "B.Mask" user "Board Geometry/Soldermask Bottom")
		(17 "Dwgs.User" user "User.Drawings")
		(19 "Cmts.User" user "User.Comments")
		(21 "Eco1.User" user "User.Eco1")
		(23 "Eco2.User" user "User.Eco2")
		(25 "Edge.Cuts" user "Board Geometry/Outline")
		(27 "Margin" user)
		(31 "F.CrtYd" user "Package Geometry/Place Bound Top")
		(29 "B.CrtYd" user "Package Geometry/Place Bound Bottom")
		(35 "F.Fab" user "Ref Des/Assembly Top")
		(33 "B.Fab" user "Ref Des/Assembly Bottom")
	)
	(footprint ""
		(layer "B.Cu")
		(at 397.880078 -324.812152)
		(property "Reference" "R462"
			(at 0 0 0)
			(layer "B.SilkS")
			(hide yes)
			(effects
				(font
					(size 1.27 1.27)
				)
				(justify mirror)
			)
		)
		(property "Value" ""
			(at 0 0 0)
			(layer "B.Fab")
			(effects
				(font
					(size 1.27 1.27)
				)
				(justify mirror)
			)
		)
		(duplicate_pad_numbers_are_jumpers no)
		(fp_line
			(start -0.7874 -0.4064)
			(end -0.7874 0.4064)
			(stroke
				(width 0.1524)
				(type default)
			)
			(layer "B.SilkS")
		)
		(fp_line
			(start -0.7874 0.4064)
			(end 0.7874 0.4064)
			(stroke
				(width 0.1524)
				(type default)
			)
			(layer "B.SilkS")
		)
		(fp_line
			(start 0.7874 -0.4064)
			(end -0.7874 -0.4064)
			(stroke
				(width 0.1524)
				(type default)
			)
			(layer "B.SilkS")
		)
		(fp_line
			(start 0.7874 0.4064)
			(end 0.7874 -0.4064)
			(stroke
				(width 0.1524)
				(type default)
			)
			(layer "B.SilkS")
		)
		(fp_line
			(start -0.67945 -0.3048)
			(end -0.67945 0.3048)
			(stroke
				(width 0.1)
				(type default)
			)
			(layer "B.Fab")
		)
		(fp_line
			(start -0.67945 0.3048)
			(end -0.120396 0.3048)
			(stroke
				(width 0.1)
				(type default)
			)
			(layer "B.Fab")
		)
		(fp_line
			(start -0.12065 -0.3048)
			(end -0.67945 -0.3048)
			(stroke
				(width 0.1)
				(type default)
			)
			(layer "B.Fab")
		)
		(fp_line
			(start -0.12065 -0.2794)
			(end -0.12065 -0.3048)
			(stroke
				(width 0.1)
				(type default)
			)
			(layer "B.Fab")
		)
		(fp_line
			(start -0.120396 0.2794)
			(end 0.12065 0.2794)
			(stroke
				(width 0.1)
				(type default)
			)
			(layer "B.Fab")
		)
		(fp_line
			(start -0.120396 0.3048)
			(end -0.120396 0.2794)
			(stroke
				(width 0.1)
				(type default)
			)
			(layer "B.Fab")
		)
		(fp_line
			(start 0.12065 -0.305054)
			(end 0.12065 -0.2794)
			(stroke
				(width 0.1)
				(type default)
			)
			(layer "B.Fab")
		)
		(fp_line
			(start 0.12065 -0.2794)
			(end -0.12065 -0.2794)
			(stroke
				(width 0.1)
				(type default)
			)
			(layer "B.Fab")
		)
		(fp_line
			(start 0.12065 0.2794)
			(end 0.12065 0.3048)
			(stroke
				(width 0.1)
				(type default)
			)
			(layer "B.Fab")
		)
		(fp_line
			(start 0.12065 0.3048)
			(end 0.67945 0.3048)
			(stroke
				(width 0.1)
				(type default)
			)
			(layer "B.Fab")
		)
		(fp_line
			(start 0.67945 -0.305054)
			(end 0.12065 -0.305054)
			(stroke
				(width 0.1)
				(type default)
			)
			(layer "B.Fab")
		)
		(fp_line
			(start 0.67945 0.3048)
			(end 0.67945 -0.305054)
			(stroke
				(width 0.1)
				(type default)
			)
			(layer "B.Fab")
		)
		(pad "1" smd rect
			(at 0.40005 0)
			(size 0.4572 0.508)
			(layers "B.Cu" "B.Mask" "B.Paste")
			(net "ESPI_CPU0_CS1_N")
		)
		(pad "2" smd rect
			(at -0.40005 0)
			(size 0.4572 0.508)
			(layers "B.Cu" "B.Mask" "B.Paste")
			(net "ESPI_CPU0_R_CS1_N")
		)
	)
	(footprint ""
		(layer "B.Cu")
		(at 102.656386 -267.529564)
		(property "Reference" "C2397"
			(at 0 0 0)
			(layer "B.SilkS")
			(hide yes)
			(effects
				(font
					(size 1.27 1.27)
				)
				(justify mirror)
			)
		)
		(property "Value" ""
			(at 0 0 0)
			(layer "B.Fab")
			(effects
				(font
					(size 1.27 1.27)
				)
				(justify mirror)
			)
		)
		(duplicate_pad_numbers_are_jumpers no)
		(fp_line
			(start -0.7874 -0.4064)
			(end -0.7874 0.4064)
			(stroke
				(width 0.1524)
				(type default)
			)
			(layer "B.SilkS")
		)
		(fp_line
			(start -0.7874 0.4064)
			(end 0.7874 0.4064)
			(stroke
				(width 0.1524)
				(type default)
			)
			(layer "B.SilkS")
		)
		(fp_line
			(start 0.7874 -0.4064)
			(end -0.7874 -0.4064)
			(stroke
				(width 0.1524)
				(type default)
			)
			(layer "B.SilkS")
		)
		(fp_line
			(start 0.7874 0.4064)
			(end 0.7874 -0.4064)
			(stroke
				(width 0.1524)
				(type default)
			)
			(layer "B.SilkS")
		)
		(fp_line
			(start -0.67945 -0.3048)
			(end -0.67945 0.3048)
			(stroke
				(width 0.1)
				(type default)
			)
			(layer "B.Fab")
		)
		(fp_line
			(start -0.67945 0.3048)
			(end -0.120396 0.3048)
			(stroke
				(width 0.1)
				(type default)
			)
			(layer "B.Fab")
		)
		(fp_line
			(start -0.12065 -0.3048)
			(end -0.67945 -0.3048)
			(stroke
				(width 0.1)
				(type default)
			)
			(layer "B.Fab")
		)
		(fp_line
			(start -0.12065 -0.2794)
			(end -0.12065 -0.3048)
			(stroke
				(width 0.1)
				(type default)
			)
			(layer "B.Fab")
		)
		(fp_line
			(start -0.120396 0.2794)
			(end 0.12065 0.2794)
			(stroke
				(width 0.1)
				(type default)
			)
			(layer "B.Fab")
		)
		(fp_line
			(start -0.120396 0.3048)
			(end -0.120396 0.2794)
			(stroke
				(width 0.1)
				(type default)
			)
			(layer "B.Fab")
		)
		(fp_line
			(start 0.12065 -0.305054)
			(end 0.12065 -0.2794)
			(stroke
				(width 0.1)
				(type default)
			)
			(layer "B.Fab")
		)
		(fp_line
			(start 0.12065 -0.2794)
			(end -0.12065 -0.2794)
			(stroke
				(width 0.1)
				(type default)
			)
			(layer "B.Fab")
		)
		(fp_line
			(start 0.12065 0.2794)
			(end 0.12065 0.3048)
			(stroke
				(width 0.1)
				(type default)
			)
			(layer "B.Fab")
		)
		(fp_line
			(start 0.12065 0.3048)
			(end 0.67945 0.3048)
			(stroke
				(width 0.1)
				(type default)
			)
			(layer "B.Fab")
		)
		(fp_line
			(start 0.67945 -0.305054)
			(end 0.12065 -0.305054)
			(stroke
				(width 0.1)
				(type default)
			)
			(layer "B.Fab")
		)
		(fp_line
			(start 0.67945 0.3048)
			(end 0.67945 -0.305054)
			(stroke
				(width 0.1)
				(type default)
			)
			(layer "B.Fab")
		)
		(pad "1" smd circle
			(at 0.40005 0 180)
			(size 0 0)
			(layers "B.Cu" "B.Mask" "B.Paste")
			(net "PVDDCR_CPU1_P1")
		)
		(pad "2" smd circle
			(at -0.40005 0 180)
			(size 0 0)
			(layers "B.Cu" "B.Mask" "B.Paste")
			(net "GND")
		)
	)
	(footprint ""
		(layer "B.Cu")
		(at 429.103282 -436.414672 -90)
		(property "Reference" "R4162"
			(at 0 0 90)
			(layer "B.SilkS")
			(hide yes)
			(effects
				(font
					(size 1.27 1.27)
				)
				(justify mirror)
			)
		)
		(property "Value" ""
			(at 0 0 90)
			(layer "B.Fab")
			(effects
				(font
					(size 1.27 1.27)
				)
				(justify mirror)
			)
		)
		(duplicate_pad_numbers_are_jumpers no)
		(fp_line
			(start -0.7874 0.4064)
			(end 0.7874 0.4064)
			(stroke
				(width 0.1524)
				(type default)
			)
			(layer "B.SilkS")
		)
		(fp_line
			(start 0.7874 0.4064)
			(end 0.7874 -0.4064)
			(stroke
				(width 0.1524)
				(type default)
			)
			(layer "B.SilkS")
		)
		(fp_line
			(start -0.7874 -0.4064)
			(end -0.7874 0.4064)
			(stroke
				(width 0.1524)
				(type default)
			)
			(layer "B.SilkS")
		)
		(fp_line
			(start 0.7874 -0.4064)
			(end -0.7874 -0.4064)
			(stroke
				(width 0.1524)
				(type default)
			)
			(layer "B.SilkS")
		)
		(fp_line
			(start -0.67945 0.3048)
			(end -0.120396 0.3048)
			(stroke
				(width 0.1)
				(type default)
			)
			(layer "B.Fab")
		)
		(fp_line
			(start -0.120396 0.3048)
			(end -0.120396 0.2794)
			(stroke
				(width 0.1)
				(type default)
			)
			(layer "B.Fab")
		)
		(fp_line
			(start 0.12065 0.3048)
			(end 0.67945 0.3048)
			(stroke
				(width 0.1)
				(type default)
			)
			(layer "B.Fab")
		)
		(fp_line
			(start 0.67945 0.3048)
			(end 0.67945 -0.305054)
			(stroke
				(width 0.1)
				(type default)
			)
			(layer "B.Fab")
		)
		(fp_line
			(start -0.120396 0.2794)
			(end 0.12065 0.2794)
			(stroke
				(width 0.1)
				(type default)
			)
			(layer "B.Fab")
		)
		(fp_line
			(start 0.12065 0.2794)
			(end 0.12065 0.3048)
			(stroke
				(width 0.1)
				(type default)
			)
			(layer "B.Fab")
		)
		(fp_line
			(start -0.12065 -0.2794)
			(end -0.12065 -0.3048)
			(stroke
				(width 0.1)
				(type default)
			)
			(layer "B.Fab")
		)
		(fp_line
			(start 0.12065 -0.2794)
			(end -0.12065 -0.2794)
			(stroke
				(width 0.1)
				(type default)
			)
			(layer "B.Fab")
		)
		(fp_line
			(start -0.67945 -0.3048)
			(end -0.67945 0.3048)
			(stroke
				(width 0.1)
				(type default)
			)
			(layer "B.Fab")
		)
		(fp_line
			(start -0.12065 -0.3048)
			(end -0.67945 -0.3048)
			(stroke
				(width 0.1)
				(type default)
			)
			(layer "B.Fab")
		)
		(fp_line
			(start 0.12065 -0.305054)
			(end 0.12065 -0.2794)
			(stroke
				(width 0.1)
				(type default)
			)
			(layer "B.Fab")
		)
		(fp_line
			(start 0.67945 -0.305054)
			(end 0.12065 -0.305054)
			(stroke
				(width 0.1)
				(type default)
			)
			(layer "B.Fab")
		)
		(pad "1" smd circle
			(at 0.40005 0 90)
			(size 0 0)
			(layers "B.Cu" "B.Mask" "B.Paste")
			(net "P3V3_AUX")
		)
		(pad "2" smd circle
			(at -0.40005 0 90)
			(size 0 0)
			(layers "B.Cu" "B.Mask" "B.Paste")
			(net "GPU_3V3IO_RSVD3")
		)
	)
	(footprint ""
		(layer "B.Cu")
		(at 355.803454 -268.41831)
		(property "Reference" "C2226"
			(at 0 0 0)
			(layer "B.SilkS")
			(hide yes)
			(effects
				(font
					(size 1.27 1.27)
				)
				(justify mirror)
			)
		)
		(property "Value" ""
			(at 0 0 0)
			(layer "B.Fab")
			(effects
				(font
					(size 1.27 1.27)
				)
				(justify mirror)
			)
		)
		(duplicate_pad_numbers_are_jumpers no)
		(fp_line
			(start -0.7874 -0.4064)
			(end -0.7874 0.4064)
			(stroke
				(width 0.1524)
				(type default)
			)
			(layer "B.SilkS")
		)
		(fp_line
			(start -0.7874 0.4064)
			(end 0.7874 0.4064)
			(stroke
				(width 0.1524)
				(type default)
			)
			(layer "B.SilkS")
		)
		(fp_line
			(start 0.7874 -0.4064)
			(end -0.7874 -0.4064)
			(stroke
				(width 0.1524)
				(type default)
			)
			(layer "B.SilkS")
		)
		(fp_line
			(start 0.7874 0.4064)
			(end 0.7874 -0.4064)
			(stroke
				(width 0.1524)
				(type default)
			)
			(layer "B.SilkS")
		)
		(fp_line
			(start -0.67945 -0.3048)
			(end -0.67945 0.3048)
			(stroke
				(width 0.1)
				(type default)
			)
			(layer "B.Fab")
		)
		(fp_line
			(start -0.67945 0.3048)
			(end -0.120396 0.3048)
			(stroke
				(width 0.1)
				(type default)
			)
			(layer "B.Fab")
		)
		(fp_line
			(start -0.12065 -0.3048)
			(end -0.67945 -0.3048)
			(stroke
				(width 0.1)
				(type default)
			)
			(layer "B.Fab")
		)
		(fp_line
			(start -0.12065 -0.2794)
			(end -0.12065 -0.3048)
			(stroke
				(width 0.1)
				(type default)
			)
			(layer "B.Fab")
		)
		(fp_line
			(start -0.120396 0.2794)
			(end 0.12065 0.2794)
			(stroke
				(width 0.1)
				(type default)
			)
			(layer "B.Fab")
		)
		(fp_line
			(start -0.120396 0.3048)
			(end -0.120396 0.2794)
			(stroke
				(width 0.1)
				(type default)
			)
			(layer "B.Fab")
		)
		(fp_line
			(start 0.12065 -0.305054)
			(end 0.12065 -0.2794)
			(stroke
				(width 0.1)
				(type default)
			)
			(layer "B.Fab")
		)
		(fp_line
			(start 0.12065 -0.2794)
			(end -0.12065 -0.2794)
			(stroke
				(width 0.1)
				(type default)
			)
			(layer "B.Fab")
		)
		(fp_line
			(start 0.12065 0.2794)
			(end 0.12065 0.3048)
			(stroke
				(width 0.1)
				(type default)
			)
			(layer "B.Fab")
		)
		(fp_line
			(start 0.12065 0.3048)
			(end 0.67945 0.3048)
			(stroke
				(width 0.1)
				(type default)
			)
			(layer "B.Fab")
		)
		(fp_line
			(start 0.67945 -0.305054)
			(end 0.12065 -0.305054)
			(stroke
				(width 0.1)
				(type default)
			)
			(layer "B.Fab")
		)
		(fp_line
			(start 0.67945 0.3048)
			(end 0.67945 -0.305054)
			(stroke
				(width 0.1)
				(type default)
			)
			(layer "B.Fab")
		)
		(pad "1" smd circle
			(at 0.40005 0 180)
			(size 0 0)
			(layers "B.Cu" "B.Mask" "B.Paste")
			(net "PVDDCR_CPU1_P0")
		)
		(pad "2" smd circle
			(at -0.40005 0 180)
			(size 0 0)
			(layers "B.Cu" "B.Mask" "B.Paste")
			(net "GND")
		)
	)
	(footprint ""
		(layer "B.Cu")
		(at 190.881 -100.294948 -90)
		(property "Reference" "R269"
			(at 0 0 90)
			(layer "B.SilkS")
			(hide yes)
			(effects
				(font
					(size 1.27 1.27)
				)
				(justify mirror)
			)
		)
		(property "Value" ""
			(at 0 0 90)
			(layer "B.Fab")
			(effects
				(font
					(size 1.27 1.27)
				)
				(justify mirror)
			)
		)
		(duplicate_pad_numbers_are_jumpers no)
		(fp_line
			(start -0.7874 0.4064)
			(end 0.7874 0.4064)
			(stroke
				(width 0.1524)
				(type default)
			)
			(layer "B.SilkS")
		)
		(fp_line
			(start 0.7874 0.4064)
			(end 0.7874 -0.4064)
			(stroke
				(width 0.1524)
				(type default)
			)
			(layer "B.SilkS")
		)
		(fp_line
			(start -0.7874 -0.4064)
			(end -0.7874 0.4064)
			(stroke
				(width 0.1524)
				(type default)
			)
			(layer "B.SilkS")
		)
		(fp_line
			(start 0.7874 -0.4064)
			(end -0.7874 -0.4064)
			(stroke
				(width 0.1524)
				(type default)
			)
			(layer "B.SilkS")
		)
		(fp_line
			(start -0.67945 0.3048)
			(end -0.120396 0.3048)
			(stroke
				(width 0.1)
				(type default)
			)
			(layer "B.Fab")
		)
		(fp_line
			(start -0.120396 0.3048)
			(end -0.120396 0.2794)
			(stroke
				(width 0.1)
				(type default)
			)
			(layer "B.Fab")
		)
		(fp_line
			(start 0.12065 0.3048)
			(end 0.67945 0.3048)
			(stroke
				(width 0.1)
				(type default)
			)
			(layer "B.Fab")
		)
		(fp_line
			(start 0.67945 0.3048)
			(end 0.67945 -0.305054)
			(stroke
				(width 0.1)
				(type default)
			)
			(layer "B.Fab")
		)
		(fp_line
			(start -0.120396 0.2794)
			(end 0.12065 0.2794)
			(stroke
				(width 0.1)
				(type default)
			)
			(layer "B.Fab")
		)
		(fp_line
			(start 0.12065 0.2794)
			(end 0.12065 0.3048)
			(stroke
				(width 0.1)
				(type default)
			)
			(layer "B.Fab")
		)
		(fp_line
			(start -0.12065 -0.2794)
			(end -0.12065 -0.3048)
			(stroke
				(width 0.1)
				(type default)
			)
			(layer "B.Fab")
		)
		(fp_line
			(start 0.12065 -0.2794)
			(end -0.12065 -0.2794)
			(stroke
				(width 0.1)
				(type default)
			)
			(layer "B.Fab")
		)
		(fp_line
			(start -0.67945 -0.3048)
			(end -0.67945 0.3048)
			(stroke
				(width 0.1)
				(type default)
			)
			(layer "B.Fab")
		)
		(fp_line
			(start -0.12065 -0.3048)
			(end -0.67945 -0.3048)
			(stroke
				(width 0.1)
				(type default)
			)
			(layer "B.Fab")
		)
		(fp_line
			(start 0.12065 -0.305054)
			(end 0.12065 -0.2794)
			(stroke
				(width 0.1)
				(type default)
			)
			(layer "B.Fab")
		)
		(fp_line
			(start 0.67945 -0.305054)
			(end 0.12065 -0.305054)
			(stroke
				(width 0.1)
				(type default)
			)
			(layer "B.Fab")
		)
		(pad "1" smd circle
			(at 0.40005 0 90)
			(size 0 0)
			(layers "B.Cu" "B.Mask" "B.Paste")
			(net "CPU1_SP5R4")
		)
		(pad "2" smd circle
			(at -0.40005 0 90)
			(size 0 0)
			(layers "B.Cu" "B.Mask" "B.Paste")
			(net "FM_CPU1_SP5R4")
		)
	)
	(footprint ""
		(layer "B.Cu")
		(at 179.354734 -342.261952 -90)
		(property "Reference" "PC526_1"
			(at 0 0 90)
			(layer "B.SilkS")
			(hide yes)
			(effects
				(font
					(size 1.27 1.27)
				)
				(justify mirror)
			)
		)
		(property "Value" ""
			(at 0 0 90)
			(layer "B.Fab")
			(effects
				(font
					(size 1.27 1.27)
				)
				(justify mirror)
			)
		)
		(duplicate_pad_numbers_are_jumpers no)
		(fp_line
			(start -1.524 0.762)
			(end 1.524 0.762)
			(stroke
				(width 0.1524)
				(type default)
			)
			(layer "B.SilkS")
		)
		(fp_line
			(start 1.524 0.762)
			(end 1.524 -0.762)
			(stroke
				(width 0.1524)
				(type default)
			)
			(layer "B.SilkS")
		)
		(fp_line
			(start -1.524 -0.762)
			(end -1.524 0.762)
			(stroke
				(width 0.1524)
				(type default)
			)
			(layer "B.SilkS")
		)
		(fp_line
			(start 1.524 -0.762)
			(end -1.524 -0.762)
			(stroke
				(width 0.1524)
				(type default)
			)
			(layer "B.SilkS")
		)
		(fp_line
			(start -1.1049 0.724916)
			(end -1.1049 -0.724916)
			(stroke
				(width 0.1)
				(type default)
			)
			(layer "B.Fab")
		)
		(fp_line
			(start 1.1049 0.724916)
			(end -1.1049 0.724916)
			(stroke
				(width 0.1)
				(type default)
			)
			(layer "B.Fab")
		)
		(fp_line
			(start -1.1049 -0.724916)
			(end 1.1049 -0.724916)
			(stroke
				(width 0.1)
				(type default)
			)
			(layer "B.Fab")
		)
		(fp_line
			(start 1.1049 -0.724916)
			(end 1.1049 0.724916)
			(stroke
				(width 0.1)
				(type default)
			)
			(layer "B.Fab")
		)
		(pad "1" smd rect
			(at 0.889 0 270)
			(size 1.016 1.27)
			(layers "B.Cu" "B.Mask" "B.Paste")
			(net "PVDD11_S3_P1")
		)
		(pad "2" smd rect
			(at -0.889 0 270)
			(size 1.016 1.27)
			(layers "B.Cu" "B.Mask" "B.Paste")
			(net "GND")
		)
	)
)
